(kicad_pcb
	(version 20260206)
	(generator "pcbnew")
	(generator_version "10.0")
	(general
		(thickness 1.6)
		(legacy_teardrops no)
	)
	(paper "A4")
	(title_block
		(title "01162023_DA0F0TEBIF0_F0T_Expander_BD_F_brd_V02_OCP.brd")
		(comment 1 "Grand Teton / footprints 2061-2066 of 9728")
	)
	(layers
		(0 "F.Cu" signal "TOP")
		(4 "In1.Cu" signal "GND")
		(6 "In2.Cu" signal "VCC")
		(8 "In3.Cu" signal "VCC1")
		(10 "In4.Cu" signal "GND1")
		(12 "In5.Cu" signal "IN1")
		(14 "In6.Cu" signal "GND2")
		(16 "In7.Cu" signal "IN2")
		(18 "In8.Cu" signal "GND3")
		(20 "In9.Cu" signal "IN3")
		(22 "In10.Cu" signal "GND4")
		(24 "In11.Cu" signal "IN4")
		(26 "In12.Cu" signal "GND5")
		(28 "In13.Cu" signal "IN5")
		(30 "In14.Cu" signal "GND6")
		(32 "In15.Cu" signal "IN6")
		(34 "In16.Cu" signal "GND7")
		(2 "B.Cu" signal "BOTTOM")
		(9 "F.Adhes" user "F.Adhesive")
		(11 "B.Adhes" user "B.Adhesive")
		(13 "F.Paste" user "Package Geometry/Pastemask Top")
		(15 "B.Paste" user "Package Geometry/Pastemask Bottom")
		(5 "F.SilkS" user "Ref Des/Silkscreen Top")
		(7 "B.SilkS" user "Ref Des/Silkscreen Bottom")
		(1 "F.Mask" user "Board Geometry/Soldermask Top")
		(3 "B.Mask" user "Board Geometry/Soldermask Bottom")
		(17 "Dwgs.User" user "User.Drawings")
		(19 "Cmts.User" user "User.Comments")
		(21 "Eco1.User" user "User.Eco1")
		(23 "Eco2.User" user "User.Eco2")
		(25 "Edge.Cuts" user "Board Geometry/Outline")
		(27 "Margin" user)
		(31 "F.CrtYd" user "Package Geometry/Place Bound Top")
		(29 "B.CrtYd" user "Package Geometry/Place Bound Bottom")
		(35 "F.Fab" user "Ref Des/Assembly Top")
		(33 "B.Fab" user "Ref Des/Assembly Bottom")
	)
	(footprint ""
		(layer "F.Cu")
		(at 53.840126 -32.848042 90)
		(property "Reference" "PC685"
			(at 0 0 90)
			(layer "F.SilkS")
			(hide yes)
			(effects
				(font
					(size 1.27 1.27)
				)
			)
		)
		(property "Value" ""
			(at 0 0 90)
			(layer "F.Fab")
			(effects
				(font
					(size 1.27 1.27)
				)
			)
		)
		(duplicate_pad_numbers_are_jumpers no)
		(fp_line
			(start 0.7874 -0.4064)
			(end 0.7874 0.4064)
			(stroke
				(width 0.1524)
				(type default)
			)
			(layer "F.SilkS")
		)
		(fp_line
			(start -0.7874 -0.4064)
			(end 0.7874 -0.4064)
			(stroke
				(width 0.1524)
				(type default)
			)
			(layer "F.SilkS")
		)
		(fp_line
			(start 0.7874 0.4064)
			(end -0.7874 0.4064)
			(stroke
				(width 0.1524)
				(type default)
			)
			(layer "F.SilkS")
		)
		(fp_line
			(start -0.7874 0.4064)
			(end -0.7874 -0.4064)
			(stroke
				(width 0.1524)
				(type default)
			)
			(layer "F.SilkS")
		)
		(fp_line
			(start -0.12065 -0.305054)
			(end -0.12065 -0.2794)
			(stroke
				(width 0.1)
				(type default)
			)
			(layer "F.Fab")
		)
		(fp_line
			(start -0.67945 -0.305054)
			(end -0.12065 -0.305054)
			(stroke
				(width 0.1)
				(type default)
			)
			(layer "F.Fab")
		)
		(fp_line
			(start 0.67945 -0.3048)
			(end 0.67945 0.3048)
			(stroke
				(width 0.1)
				(type default)
			)
			(layer "F.Fab")
		)
		(fp_line
			(start 0.12065 -0.3048)
			(end 0.67945 -0.3048)
			(stroke
				(width 0.1)
				(type default)
			)
			(layer "F.Fab")
		)
		(fp_line
			(start 0.12065 -0.2794)
			(end 0.12065 -0.3048)
			(stroke
				(width 0.1)
				(type default)
			)
			(layer "F.Fab")
		)
		(fp_line
			(start -0.12065 -0.2794)
			(end 0.12065 -0.2794)
			(stroke
				(width 0.1)
				(type default)
			)
			(layer "F.Fab")
		)
		(fp_line
			(start 0.120396 0.2794)
			(end -0.12065 0.2794)
			(stroke
				(width 0.1)
				(type default)
			)
			(layer "F.Fab")
		)
		(fp_line
			(start -0.12065 0.2794)
			(end -0.12065 0.3048)
			(stroke
				(width 0.1)
				(type default)
			)
			(layer "F.Fab")
		)
		(fp_line
			(start 0.67945 0.3048)
			(end 0.120396 0.3048)
			(stroke
				(width 0.1)
				(type default)
			)
			(layer "F.Fab")
		)
		(fp_line
			(start 0.120396 0.3048)
			(end 0.120396 0.2794)
			(stroke
				(width 0.1)
				(type default)
			)
			(layer "F.Fab")
		)
		(fp_line
			(start -0.12065 0.3048)
			(end -0.67945 0.3048)
			(stroke
				(width 0.1)
				(type default)
			)
			(layer "F.Fab")
		)
		(fp_line
			(start -0.67945 0.3048)
			(end -0.67945 -0.305054)
			(stroke
				(width 0.1)
				(type default)
			)
			(layer "F.Fab")
		)
		(pad "1" smd circle
			(at -0.40005 0 90)
			(size 0 0)
			(layers "F.Cu" "F.Mask" "F.Paste")
			(net "P3V3_SSD2_CO_DV_DT")
		)
		(pad "2" smd circle
			(at 0.40005 0 90)
			(size 0 0)
			(layers "F.Cu" "F.Mask" "F.Paste")
			(net "GND")
		)
	)
	(footprint ""
		(layer "F.Cu")
		(at 8.049768 -157.812994)
		(property "Reference" "R902"
			(at 0 0 0)
			(layer "F.SilkS")
			(hide yes)
			(effects
				(font
					(size 1.27 1.27)
				)
			)
		)
		(property "Value" ""
			(at 0 0 0)
			(layer "F.Fab")
			(effects
				(font
					(size 1.27 1.27)
				)
			)
		)
		(duplicate_pad_numbers_are_jumpers no)
		(fp_line
			(start -0.7874 -0.4064)
			(end 0.7874 -0.4064)
			(stroke
				(width 0.1524)
				(type default)
			)
			(layer "F.SilkS")
		)
		(fp_line
			(start -0.7874 0.4064)
			(end -0.7874 -0.4064)
			(stroke
				(width 0.1524)
				(type default)
			)
			(layer "F.SilkS")
		)
		(fp_line
			(start 0.7874 -0.4064)
			(end 0.7874 0.4064)
			(stroke
				(width 0.1524)
				(type default)
			)
			(layer "F.SilkS")
		)
		(fp_line
			(start 0.7874 0.4064)
			(end -0.7874 0.4064)
			(stroke
				(width 0.1524)
				(type default)
			)
			(layer "F.SilkS")
		)
		(fp_line
			(start -0.67945 -0.305054)
			(end -0.12065 -0.305054)
			(stroke
				(width 0.1)
				(type default)
			)
			(layer "F.Fab")
		)
		(fp_line
			(start -0.67945 0.3048)
			(end -0.67945 -0.305054)
			(stroke
				(width 0.1)
				(type default)
			)
			(layer "F.Fab")
		)
		(fp_line
			(start -0.12065 -0.305054)
			(end -0.12065 -0.2794)
			(stroke
				(width 0.1)
				(type default)
			)
			(layer "F.Fab")
		)
		(fp_line
			(start -0.12065 -0.2794)
			(end 0.12065 -0.2794)
			(stroke
				(width 0.1)
				(type default)
			)
			(layer "F.Fab")
		)
		(fp_line
			(start -0.12065 0.2794)
			(end -0.12065 0.3048)
			(stroke
				(width 0.1)
				(type default)
			)
			(layer "F.Fab")
		)
		(fp_line
			(start -0.12065 0.3048)
			(end -0.67945 0.3048)
			(stroke
				(width 0.1)
				(type default)
			)
			(layer "F.Fab")
		)
		(fp_line
			(start 0.120396 0.2794)
			(end -0.12065 0.2794)
			(stroke
				(width 0.1)
				(type default)
			)
			(layer "F.Fab")
		)
		(fp_line
			(start 0.120396 0.3048)
			(end 0.120396 0.2794)
			(stroke
				(width 0.1)
				(type default)
			)
			(layer "F.Fab")
		)
		(fp_line
			(start 0.12065 -0.3048)
			(end 0.67945 -0.3048)
			(stroke
				(width 0.1)
				(type default)
			)
			(layer "F.Fab")
		)
		(fp_line
			(start 0.12065 -0.2794)
			(end 0.12065 -0.3048)
			(stroke
				(width 0.1)
				(type default)
			)
			(layer "F.Fab")
		)
		(fp_line
			(start 0.67945 -0.3048)
			(end 0.67945 0.3048)
			(stroke
				(width 0.1)
				(type default)
			)
			(layer "F.Fab")
		)
		(fp_line
			(start 0.67945 0.3048)
			(end 0.120396 0.3048)
			(stroke
				(width 0.1)
				(type default)
			)
			(layer "F.Fab")
		)
		(pad "1" smd circle
			(at -0.40005 0)
			(size 0 0)
			(layers "F.Cu" "F.Mask" "F.Paste")
			(net "P3V3_AUX")
		)
		(pad "2" smd circle
			(at 0.40005 0)
			(size 0 0)
			(layers "F.Cu" "F.Mask" "F.Paste")
			(net "PWRGD_P12V_NIC0_CO")
		)
	)
	(footprint ""
		(layer "F.Cu")
		(at 380.419102 -59.574684 90)
		(property "Reference" "PC564"
			(at 0 0 90)
			(layer "F.SilkS")
			(hide yes)
			(effects
				(font
					(size 1.27 1.27)
				)
			)
		)
		(property "Value" ""
			(at 0 0 90)
			(layer "F.Fab")
			(effects
				(font
					(size 1.27 1.27)
				)
			)
		)
		(duplicate_pad_numbers_are_jumpers no)
		(fp_line
			(start 0.7874 -0.4064)
			(end 0.7874 0.4064)
			(stroke
				(width 0.1524)
				(type default)
			)
			(layer "F.SilkS")
		)
		(fp_line
			(start -0.7874 -0.4064)
			(end 0.7874 -0.4064)
			(stroke
				(width 0.1524)
				(type default)
			)
			(layer "F.SilkS")
		)
		(fp_line
			(start 0.7874 0.4064)
			(end -0.7874 0.4064)
			(stroke
				(width 0.1524)
				(type default)
			)
			(layer "F.SilkS")
		)
		(fp_line
			(start -0.7874 0.4064)
			(end -0.7874 -0.4064)
			(stroke
				(width 0.1524)
				(type default)
			)
			(layer "F.SilkS")
		)
		(fp_line
			(start -0.12065 -0.305054)
			(end -0.12065 -0.2794)
			(stroke
				(width 0.1)
				(type default)
			)
			(layer "F.Fab")
		)
		(fp_line
			(start -0.67945 -0.305054)
			(end -0.12065 -0.305054)
			(stroke
				(width 0.1)
				(type default)
			)
			(layer "F.Fab")
		)
		(fp_line
			(start 0.67945 -0.3048)
			(end 0.67945 0.3048)
			(stroke
				(width 0.1)
				(type default)
			)
			(layer "F.Fab")
		)
		(fp_line
			(start 0.12065 -0.3048)
			(end 0.67945 -0.3048)
			(stroke
				(width 0.1)
				(type default)
			)
			(layer "F.Fab")
		)
		(fp_line
			(start 0.12065 -0.2794)
			(end 0.12065 -0.3048)
			(stroke
				(width 0.1)
				(type default)
			)
			(layer "F.Fab")
		)
		(fp_line
			(start -0.12065 -0.2794)
			(end 0.12065 -0.2794)
			(stroke
				(width 0.1)
				(type default)
			)
			(layer "F.Fab")
		)
		(fp_line
			(start 0.120396 0.2794)
			(end -0.12065 0.2794)
			(stroke
				(width 0.1)
				(type default)
			)
			(layer "F.Fab")
		)
		(fp_line
			(start -0.12065 0.2794)
			(end -0.12065 0.3048)
			(stroke
				(width 0.1)
				(type default)
			)
			(layer "F.Fab")
		)
		(fp_line
			(start 0.67945 0.3048)
			(end 0.120396 0.3048)
			(stroke
				(width 0.1)
				(type default)
			)
			(layer "F.Fab")
		)
		(fp_line
			(start 0.120396 0.3048)
			(end 0.120396 0.2794)
			(stroke
				(width 0.1)
				(type default)
			)
			(layer "F.Fab")
		)
		(fp_line
			(start -0.12065 0.3048)
			(end -0.67945 0.3048)
			(stroke
				(width 0.1)
				(type default)
			)
			(layer "F.Fab")
		)
		(fp_line
			(start -0.67945 0.3048)
			(end -0.67945 -0.305054)
			(stroke
				(width 0.1)
				(type default)
			)
			(layer "F.Fab")
		)
		(pad "1" smd circle
			(at -0.40005 0 90)
			(size 0 0)
			(layers "F.Cu" "F.Mask" "F.Paste")
			(net "P5V_AUX")
		)
		(pad "2" smd circle
			(at 0.40005 0 90)
			(size 0 0)
			(layers "F.Cu" "F.Mask" "F.Paste")
			(net "GND")
		)
	)
	(footprint ""
		(layer "F.Cu")
		(at 267.871702 -343.952322 90)
		(property "Reference" "C2341"
			(at 0 0 90)
			(layer "F.SilkS")
			(hide yes)
			(effects
				(font
					(size 1.27 1.27)
				)
			)
		)
		(property "Value" ""
			(at 0 0 90)
			(layer "F.Fab")
			(effects
				(font
					(size 1.27 1.27)
				)
			)
		)
		(duplicate_pad_numbers_are_jumpers no)
		(fp_line
			(start 0.299974 -0.150114)
			(end 0.299974 0.150114)
			(stroke
				(width 0.1)
				(type default)
			)
			(layer "F.Fab")
		)
		(fp_line
			(start -0.299974 -0.150114)
			(end 0.299974 -0.150114)
			(stroke
				(width 0.1)
				(type default)
			)
			(layer "F.Fab")
		)
		(fp_line
			(start 0.299974 0.150114)
			(end -0.299974 0.150114)
			(stroke
				(width 0.1)
				(type default)
			)
			(layer "F.Fab")
		)
		(fp_line
			(start -0.299974 0.150114)
			(end -0.299974 -0.150114)
			(stroke
				(width 0.1)
				(type default)
			)
			(layer "F.Fab")
		)
		(pad "1" smd rect
			(at -0.2667 0 90)
			(size 0.3048 0.381)
			(layers "F.Cu" "F.Mask" "F.Paste")
			(net "P5E_PEX2_STN4_TX_DP<79>")
		)
		(pad "2" smd rect
			(at 0.2667 0 90)
			(size 0.3048 0.381)
			(layers "F.Cu" "F.Mask" "F.Paste")
			(net "P5E_PEX2_STN4_TX_C_DP<79>")
		)
	)
	(footprint ""
		(layer "F.Cu")
		(at 110.767114 -157.595824)
		(property "Reference" "PC30"
			(at 0 0 0)
			(layer "F.SilkS")
			(hide yes)
			(effects
				(font
					(size 1.27 1.27)
				)
			)
		)
		(property "Value" ""
			(at 0 0 0)
			(layer "F.Fab")
			(effects
				(font
					(size 1.27 1.27)
				)
			)
		)
		(duplicate_pad_numbers_are_jumpers no)
		(fp_line
			(start -0.7874 -0.4064)
			(end 0.7874 -0.4064)
			(stroke
				(width 0.1524)
				(type default)
			)
			(layer "F.SilkS")
		)
		(fp_line
			(start -0.7874 0.4064)
			(end -0.7874 -0.4064)
			(stroke
				(width 0.1524)
				(type default)
			)
			(layer "F.SilkS")
		)
		(fp_line
			(start 0.7874 -0.4064)
			(end 0.7874 0.4064)
			(stroke
				(width 0.1524)
				(type default)
			)
			(layer "F.SilkS")
		)
		(fp_line
			(start 0.7874 0.4064)
			(end -0.7874 0.4064)
			(stroke
				(width 0.1524)
				(type default)
			)
			(layer "F.SilkS")
		)
		(fp_line
			(start -0.67945 -0.305054)
			(end -0.12065 -0.305054)
			(stroke
				(width 0.1)
				(type default)
			)
			(layer "F.Fab")
		)
		(fp_line
			(start -0.67945 0.3048)
			(end -0.67945 -0.305054)
			(stroke
				(width 0.1)
				(type default)
			)
			(layer "F.Fab")
		)
		(fp_line
			(start -0.12065 -0.305054)
			(end -0.12065 -0.2794)
			(stroke
				(width 0.1)
				(type default)
			)
			(layer "F.Fab")
		)
		(fp_line
			(start -0.12065 -0.2794)
			(end 0.12065 -0.2794)
			(stroke
				(width 0.1)
				(type default)
			)
			(layer "F.Fab")
		)
		(fp_line
			(start -0.12065 0.2794)
			(end -0.12065 0.3048)
			(stroke
				(width 0.1)
				(type default)
			)
			(layer "F.Fab")
		)
		(fp_line
			(start -0.12065 0.3048)
			(end -0.67945 0.3048)
			(stroke
				(width 0.1)
				(type default)
			)
			(layer "F.Fab")
		)
		(fp_line
			(start 0.120396 0.2794)
			(end -0.12065 0.2794)
			(stroke
				(width 0.1)
				(type default)
			)
			(layer "F.Fab")
		)
		(fp_line
			(start 0.120396 0.3048)
			(end 0.120396 0.2794)
			(stroke
				(width 0.1)
				(type default)
			)
			(layer "F.Fab")
		)
		(fp_line
			(start 0.12065 -0.3048)
			(end 0.67945 -0.3048)
			(stroke
				(width 0.1)
				(type default)
			)
			(layer "F.Fab")
		)
		(fp_line
			(start 0.12065 -0.2794)
			(end 0.12065 -0.3048)
			(stroke
				(width 0.1)
				(type default)
			)
			(layer "F.Fab")
		)
		(fp_line
			(start 0.67945 -0.3048)
			(end 0.67945 0.3048)
			(stroke
				(width 0.1)
				(type default)
			)
			(layer "F.Fab")
		)
		(fp_line
			(start 0.67945 0.3048)
			(end 0.120396 0.3048)
			(stroke
				(width 0.1)
				(type default)
			)
			(layer "F.Fab")
		)
		(pad "1" smd circle
			(at -0.40005 0)
			(size 0 0)
			(layers "F.Cu" "F.Mask" "F.Paste")
			(net "SW_P12V_P3V3_AUX_FLT")
		)
		(pad "2" smd circle
			(at 0.40005 0)
			(size 0 0)
			(layers "F.Cu" "F.Mask" "F.Paste")
			(net "GND")
		)
	)
	(footprint ""
		(layer "F.Cu")
		(at 251.42571 -159.082994 -90)
		(property "Reference" "PD93"
			(at 4.142994 -2.72796 90)
			(unlocked yes)
			(layer "F.SilkS")
			(effects
				(font
					(size 0.7874 0.5842)
					(thickness 0.1524)
				)
				(justify left)
			)
		)
		(property "Value" ""
			(at 0 0 270)
			(layer "F.Fab")
			(effects
				(font
					(size 1.27 1.27)
				)
			)
		)
		(duplicate_pad_numbers_are_jumpers no)
		(fp_line
			(start -3.656584 1.970024)
			(end 4.240784 1.970024)
			(stroke
				(width 0.1524)
				(type default)
			)
			(layer "F.SilkS")
		)
		(fp_line
			(start 4.240784 1.970024)
			(end 4.240784 -1.970024)
			(stroke
				(width 0.1524)
				(type default)
			)
			(layer "F.SilkS")
		)
		(fp_line
			(start -3.656584 -1.970024)
			(end -3.656584 1.970024)
			(stroke
				(width 0.1524)
				(type default)
			)
			(layer "F.SilkS")
		)
		(fp_line
			(start 4.240784 -1.970024)
			(end -3.656584 -1.970024)
			(stroke
				(width 0.1524)
				(type default)
			)
			(layer "F.SilkS")
		)
		(fp_poly
			(pts
				(xy 3.580384 1.970024) (xy 3.580384 -1.970024) (xy 4.240784 -1.970024) (xy 4.240784 1.970024)
			)
			(stroke
				(width 0)
				(type default)
			)
			(fill yes)
			(layer "F.SilkS")
		)
		(fp_line
			(start -2.3749 1.970024)
			(end 2.3749 1.970024)
			(stroke
				(width 0.1)
				(type default)
			)
			(layer "F.Fab")
		)
		(fp_line
			(start 2.3749 1.970024)
			(end 2.3749 -1.970024)
			(stroke
				(width 0.1)
				(type default)
			)
			(layer "F.Fab")
		)
		(fp_line
			(start -2.3749 -1.970024)
			(end -2.3749 1.970024)
			(stroke
				(width 0.1)
				(type default)
			)
			(layer "F.Fab")
		)
		(fp_line
			(start 2.3749 -1.970024)
			(end -2.3749 -1.970024)
			(stroke
				(width 0.1)
				(type default)
			)
			(layer "F.Fab")
		)
		(fp_text user "+"
			(at -4.9784 -0.23495 270)
			(unlocked yes)
			(layer "F.Fab")
			(effects
				(font
					(size 1.905 1.4224)
					(thickness 0.1524)
				)
				(justify left)
			)
		)
		(fp_text user "-"
			(at 4.1656 -0.23495 270)
			(unlocked yes)
			(layer "F.Fab")
			(effects
				(font
					(size 1.905 1.4224)
					(thickness 0.1524)
				)
				(justify left)
			)
		)
		(pad "A" smd rect
			(at -2.450084 0 270)
			(size 2.159 2.2606)
			(layers "F.Cu" "F.Mask" "F.Paste")
			(net "GND")
		)
		(pad "C" smd rect
			(at 2.450084 0 270)
			(size 2.159 2.2606)
			(layers "F.Cu" "F.Mask" "F.Paste")
			(net "P12V_AUX")
		)
	)
)
